(kicad_pcb
	(version 20260206)
	(generator "pcbnew")
	(generator_version "10.0")
	(general
		(thickness 1.6)
		(legacy_teardrops no)
	)
	(paper "A4")
	(title_block
		(title "01162023_DA0F0TEBIF0_F0T_Expander_BD_F_brd_V02_OCP.brd")
		(comment 1 "Grand Teton / footprints 3492-3498 of 9728")
	)
	(layers
		(0 "F.Cu" signal "TOP")
		(4 "In1.Cu" signal "GND")
		(6 "In2.Cu" signal "VCC")
		(8 "In3.Cu" signal "VCC1")
		(10 "In4.Cu" signal "GND1")
		(12 "In5.Cu" signal "IN1")
		(14 "In6.Cu" signal "GND2")
		(16 "In7.Cu" signal "IN2")
		(18 "In8.Cu" signal "GND3")
		(20 "In9.Cu" signal "IN3")
		(22 "In10.Cu" signal "GND4")
		(24 "In11.Cu" signal "IN4")
		(26 "In12.Cu" signal "GND5")
		(28 "In13.Cu" signal "IN5")
		(30 "In14.Cu" signal "GND6")
		(32 "In15.Cu" signal "IN6")
		(34 "In16.Cu" signal "GND7")
		(2 "B.Cu" signal "BOTTOM")
		(9 "F.Adhes" user "F.Adhesive")
		(11 "B.Adhes" user "B.Adhesive")
		(13 "F.Paste" user "Package Geometry/Pastemask Top")
		(15 "B.Paste" user "Package Geometry/Pastemask Bottom")
		(5 "F.SilkS" user "Ref Des/Silkscreen Top")
		(7 "B.SilkS" user "Ref Des/Silkscreen Bottom")
		(1 "F.Mask" user "Board Geometry/Soldermask Top")
		(3 "B.Mask" user "Board Geometry/Soldermask Bottom")
		(17 "Dwgs.User" user "User.Drawings")
		(19 "Cmts.User" user "User.Comments")
		(21 "Eco1.User" user "User.Eco1")
		(23 "Eco2.User" user "User.Eco2")
		(25 "Edge.Cuts" user "Board Geometry/Outline")
		(27 "Margin" user)
		(31 "F.CrtYd" user "Package Geometry/Place Bound Top")
		(29 "B.CrtYd" user "Package Geometry/Place Bound Bottom")
		(35 "F.Fab" user "Ref Des/Assembly Top")
		(33 "B.Fab" user "Ref Des/Assembly Bottom")
	)
	(footprint ""
		(layer "F.Cu")
		(at 224.518982 -308.568598 180)
		(property "Reference" "PU17"
			(at 3.716782 -4.150868 0)
			(unlocked yes)
			(layer "F.SilkS")
			(effects
				(font
					(size 0.7874 0.5842)
					(thickness 0.1524)
				)
				(justify left)
			)
		)
		(property "Value" ""
			(at 0 0 180)
			(layer "F.Fab")
			(effects
				(font
					(size 1.27 1.27)
				)
			)
		)
		(duplicate_pad_numbers_are_jumpers no)
		(fp_line
			(start 1.549908 2.050034)
			(end 1.549908 1.9304)
			(stroke
				(width 0.1524)
				(type default)
			)
			(layer "F.SilkS")
		)
		(fp_line
			(start 1.549908 -1.9812)
			(end 1.549908 -2.050034)
			(stroke
				(width 0.1524)
				(type default)
			)
			(layer "F.SilkS")
		)
		(fp_line
			(start 1.549908 -2.050034)
			(end 0.5842 -2.050034)
			(stroke
				(width 0.1524)
				(type default)
			)
			(layer "F.SilkS")
		)
		(fp_line
			(start 0.3048 -2.4638)
			(end 0.3048 -3.2258)
			(stroke
				(width 0.1524)
				(type default)
			)
			(layer "F.SilkS")
		)
		(fp_line
			(start 0 2.050034)
			(end 1.549908 2.050034)
			(stroke
				(width 0.1524)
				(type default)
			)
			(layer "F.SilkS")
		)
		(fp_line
			(start -0.3048 2.4638)
			(end -0.3048 3.2258)
			(stroke
				(width 0.1524)
				(type default)
			)
			(layer "F.SilkS")
		)
		(fp_line
			(start -0.5842 -2.050034)
			(end -1.549908 -2.050034)
			(stroke
				(width 0.1524)
				(type default)
			)
			(layer "F.SilkS")
		)
		(fp_line
			(start -1.549908 2.050034)
			(end -0.5842 2.050034)
			(stroke
				(width 0.1524)
				(type default)
			)
			(layer "F.SilkS")
		)
		(fp_line
			(start -1.549908 1.9812)
			(end -1.549908 2.050034)
			(stroke
				(width 0.1524)
				(type default)
			)
			(layer "F.SilkS")
		)
		(fp_line
			(start -1.549908 -2.050034)
			(end -1.549908 -1.9812)
			(stroke
				(width 0.1524)
				(type default)
			)
			(layer "F.SilkS")
		)
		(fp_line
			(start -1.9812 0)
			(end -2.3622 0)
			(stroke
				(width 0.1524)
				(type default)
			)
			(layer "F.SilkS")
		)
		(fp_poly
			(pts
				(xy -2.9464 -2.208022) (xy -2.9464 -1.192022) (xy -1.9304 -1.700022)
			)
			(stroke
				(width 0)
				(type default)
			)
			(fill yes)
			(layer "F.SilkS")
		)
		(fp_line
			(start 1.549908 2.050034)
			(end 1.549908 -2.050034)
			(stroke
				(width 0.1)
				(type default)
			)
			(layer "F.Fab")
		)
		(fp_line
			(start 1.549908 -2.050034)
			(end -1.549908 -2.050034)
			(stroke
				(width 0.1)
				(type default)
			)
			(layer "F.Fab")
		)
		(fp_line
			(start 0.3048 -2.4638)
			(end 0.3048 -3.2258)
			(stroke
				(width 0.1)
				(type default)
			)
			(layer "F.Fab")
		)
		(fp_line
			(start -0.3048 2.4638)
			(end -0.3048 3.2258)
			(stroke
				(width 0.1)
				(type default)
			)
			(layer "F.Fab")
		)
		(fp_line
			(start -1.549908 2.050034)
			(end 1.549908 2.050034)
			(stroke
				(width 0.1)
				(type default)
			)
			(layer "F.Fab")
		)
		(fp_line
			(start -1.549908 -2.050034)
			(end -1.549908 2.050034)
			(stroke
				(width 0.1)
				(type default)
			)
			(layer "F.Fab")
		)
		(fp_line
			(start -1.9812 0)
			(end -2.3622 0)
			(stroke
				(width 0.1)
				(type default)
			)
			(layer "F.Fab")
		)
		(fp_poly
			(pts
				(xy -2.9464 -2.208022) (xy -2.9464 -1.192022) (xy -1.9304 -1.700022)
			)
			(stroke
				(width 0)
				(type default)
			)
			(fill yes)
			(layer "F.Fab")
		)
		(fp_text user "11_18"
			(at 2.512568 0.9906 90)
			(unlocked yes)
			(layer "F.SilkS")
			(effects
				(font
					(size 0.635 0.4064)
					(thickness 0.1524)
				)
			)
		)
		(fp_text user "19"
			(at 1.919732 -2.676398 90)
			(unlocked yes)
			(layer "F.SilkS")
			(effects
				(font
					(size 0.635 0.4064)
					(thickness 0.1524)
				)
			)
		)
		(fp_text user "9"
			(at -1.814068 2.429002 90)
			(unlocked yes)
			(layer "F.SilkS")
			(effects
				(font
					(size 0.635 0.4064)
					(thickness 0.1524)
				)
			)
		)
		(fp_text user "11_18"
			(at 2.512568 0.9906 90)
			(unlocked yes)
			(layer "F.Fab")
			(effects
				(font
					(size 0.635 0.4064)
					(thickness 0.1524)
				)
			)
		)
		(fp_text user "19"
			(at 2.410968 -2.159 90)
			(unlocked yes)
			(layer "F.Fab")
			(effects
				(font
					(size 0.635 0.4064)
					(thickness 0.1524)
				)
			)
		)
		(fp_text user "9"
			(at -2.338832 2.0574 90)
			(unlocked yes)
			(layer "F.Fab")
			(effects
				(font
					(size 0.635 0.4064)
					(thickness 0.1524)
				)
			)
		)
		(pad "1" smd rect
			(at -1.35001 -1.700022 270)
			(size 0.3048 0.9144)
			(layers "F.Cu" "F.Mask" "F.Paste")
			(net "SW_P1V25_PEX1_BT")
		)
		(pad "2" smd rect
			(at -1.400048 -1.199896 270)
			(size 0.1778 0.8128)
			(layers "F.Cu" "F.Mask" "F.Paste")
			(net "GND")
		)
		(pad "3" smd rect
			(at -1.400048 -0.8001 270)
			(size 0.1778 0.8128)
			(layers "F.Cu" "F.Mask" "F.Paste")
			(net "P1V25_PEX1_CS")
		)
		(pad "4" smd rect
			(at -1.400048 -0.40005 270)
			(size 0.1778 0.8128)
			(layers "F.Cu" "F.Mask" "F.Paste")
			(net "GND")
		)
		(pad "5" smd rect
			(at -1.400048 0 270)
			(size 0.1778 0.8128)
			(layers "F.Cu" "F.Mask" "F.Paste")
			(net "P1V25_PEX1_REF")
		)
		(pad "6" smd rect
			(at -1.400048 0.40005 270)
			(size 0.1778 0.8128)
			(layers "F.Cu" "F.Mask" "F.Paste")
			(net "SH_P1V25_PEX1_FB_N")
		)
		(pad "7" smd rect
			(at -1.400048 0.8001 270)
			(size 0.1778 0.8128)
			(layers "F.Cu" "F.Mask" "F.Paste")
			(net "P1V25_PEX1_FB")
		)
		(pad "8" smd rect
			(at -1.400048 1.199896 270)
			(size 0.1778 0.8128)
			(layers "F.Cu" "F.Mask" "F.Paste")
			(net "P1V25_PEX1_EN")
		)
		(pad "9" smd rect
			(at -1.400048 1.700022 270)
			(size 0.3048 0.8128)
			(layers "F.Cu" "F.Mask" "F.Paste")
			(net "PWRGD_P1V25_PEX1")
		)
		(pad "10" smd rect
			(at -0.299974 1.299972 180)
			(size 0.3048 2.0066)
			(layers "F.Cu" "F.Mask" "F.Paste")
			(net "SW_P12V_P1V25_PEX1_FLT")
		)
		(pad "11_18" smd circle
			(at 1.175004 0.275082 180)
			(size 0 0)
			(layers "F.Cu" "F.Mask" "F.Paste")
			(net "GND")
		)
		(pad "19" smd rect
			(at 1.400048 -1.700022 90)
			(size 0.3048 0.8128)
			(layers "F.Cu" "F.Mask" "F.Paste")
			(net "P1V25_PEX1_VCC")
		)
		(pad "20" smd rect
			(at 0.299974 -1.299972 180)
			(size 0.3048 2.0066)
			(layers "F.Cu" "F.Mask" "F.Paste")
			(net "SW_P1V25_PEX1_PH")
		)
		(pad "21" smd rect
			(at -0.299974 -1.299972 180)
			(size 0.3048 2.0066)
			(layers "F.Cu" "F.Mask" "F.Paste")
			(net "SW_P12V_P1V25_PEX1_FLT")
		)
	)
	(footprint ""
		(layer "F.Cu")
		(at 144.506442 -252.356874 -90)
		(property "Reference" "R1287"
			(at 0 0 270)
			(layer "F.SilkS")
			(hide yes)
			(effects
				(font
					(size 1.27 1.27)
				)
			)
		)
		(property "Value" ""
			(at 0 0 270)
			(layer "F.Fab")
			(effects
				(font
					(size 1.27 1.27)
				)
			)
		)
		(duplicate_pad_numbers_are_jumpers no)
		(fp_line
			(start -0.7874 0.4064)
			(end -0.7874 -0.4064)
			(stroke
				(width 0.1524)
				(type default)
			)
			(layer "F.SilkS")
		)
		(fp_line
			(start 0.7874 0.4064)
			(end -0.7874 0.4064)
			(stroke
				(width 0.1524)
				(type default)
			)
			(layer "F.SilkS")
		)
		(fp_line
			(start -0.7874 -0.4064)
			(end 0.7874 -0.4064)
			(stroke
				(width 0.1524)
				(type default)
			)
			(layer "F.SilkS")
		)
		(fp_line
			(start 0.7874 -0.4064)
			(end 0.7874 0.4064)
			(stroke
				(width 0.1524)
				(type default)
			)
			(layer "F.SilkS")
		)
		(fp_line
			(start -0.67945 0.3048)
			(end -0.67945 -0.305054)
			(stroke
				(width 0.1)
				(type default)
			)
			(layer "F.Fab")
		)
		(fp_line
			(start -0.12065 0.3048)
			(end -0.67945 0.3048)
			(stroke
				(width 0.1)
				(type default)
			)
			(layer "F.Fab")
		)
		(fp_line
			(start 0.120396 0.3048)
			(end 0.120396 0.2794)
			(stroke
				(width 0.1)
				(type default)
			)
			(layer "F.Fab")
		)
		(fp_line
			(start 0.67945 0.3048)
			(end 0.120396 0.3048)
			(stroke
				(width 0.1)
				(type default)
			)
			(layer "F.Fab")
		)
		(fp_line
			(start -0.12065 0.2794)
			(end -0.12065 0.3048)
			(stroke
				(width 0.1)
				(type default)
			)
			(layer "F.Fab")
		)
		(fp_line
			(start 0.120396 0.2794)
			(end -0.12065 0.2794)
			(stroke
				(width 0.1)
				(type default)
			)
			(layer "F.Fab")
		)
		(fp_line
			(start -0.12065 -0.2794)
			(end 0.12065 -0.2794)
			(stroke
				(width 0.1)
				(type default)
			)
			(layer "F.Fab")
		)
		(fp_line
			(start 0.12065 -0.2794)
			(end 0.12065 -0.3048)
			(stroke
				(width 0.1)
				(type default)
			)
			(layer "F.Fab")
		)
		(fp_line
			(start 0.12065 -0.3048)
			(end 0.67945 -0.3048)
			(stroke
				(width 0.1)
				(type default)
			)
			(layer "F.Fab")
		)
		(fp_line
			(start 0.67945 -0.3048)
			(end 0.67945 0.3048)
			(stroke
				(width 0.1)
				(type default)
			)
			(layer "F.Fab")
		)
		(fp_line
			(start -0.67945 -0.305054)
			(end -0.12065 -0.305054)
			(stroke
				(width 0.1)
				(type default)
			)
			(layer "F.Fab")
		)
		(fp_line
			(start -0.12065 -0.305054)
			(end -0.12065 -0.2794)
			(stroke
				(width 0.1)
				(type default)
			)
			(layer "F.Fab")
		)
		(pad "1" smd circle
			(at -0.40005 0 270)
			(size 0 0)
			(layers "F.Cu" "F.Mask" "F.Paste")
			(net "GND")
		)
		(pad "2" smd circle
			(at 0.40005 0 270)
			(size 0 0)
			(layers "F.Cu" "F.Mask" "F.Paste")
			(net "PEX1_DBG_MODE3")
		)
	)
	(footprint ""
		(layer "F.Cu")
		(at 344.511884 -109.626654 180)
		(property "Reference" "R956"
			(at 0 0 180)
			(layer "F.SilkS")
			(hide yes)
			(effects
				(font
					(size 1.27 1.27)
				)
			)
		)
		(property "Value" ""
			(at 0 0 180)
			(layer "F.Fab")
			(effects
				(font
					(size 1.27 1.27)
				)
			)
		)
		(duplicate_pad_numbers_are_jumpers no)
		(fp_line
			(start 0.7874 0.4064)
			(end -0.7874 0.4064)
			(stroke
				(width 0.1524)
				(type default)
			)
			(layer "F.SilkS")
		)
		(fp_line
			(start 0.7874 -0.4064)
			(end 0.7874 0.4064)
			(stroke
				(width 0.1524)
				(type default)
			)
			(layer "F.SilkS")
		)
		(fp_line
			(start -0.7874 0.4064)
			(end -0.7874 -0.4064)
			(stroke
				(width 0.1524)
				(type default)
			)
			(layer "F.SilkS")
		)
		(fp_line
			(start -0.7874 -0.4064)
			(end 0.7874 -0.4064)
			(stroke
				(width 0.1524)
				(type default)
			)
			(layer "F.SilkS")
		)
		(fp_line
			(start 0.67945 0.3048)
			(end 0.120396 0.3048)
			(stroke
				(width 0.1)
				(type default)
			)
			(layer "F.Fab")
		)
		(fp_line
			(start 0.67945 -0.3048)
			(end 0.67945 0.3048)
			(stroke
				(width 0.1)
				(type default)
			)
			(layer "F.Fab")
		)
		(fp_line
			(start 0.12065 -0.2794)
			(end 0.12065 -0.3048)
			(stroke
				(width 0.1)
				(type default)
			)
			(layer "F.Fab")
		)
		(fp_line
			(start 0.12065 -0.3048)
			(end 0.67945 -0.3048)
			(stroke
				(width 0.1)
				(type default)
			)
			(layer "F.Fab")
		)
		(fp_line
			(start 0.120396 0.3048)
			(end 0.120396 0.2794)
			(stroke
				(width 0.1)
				(type default)
			)
			(layer "F.Fab")
		)
		(fp_line
			(start 0.120396 0.2794)
			(end -0.12065 0.2794)
			(stroke
				(width 0.1)
				(type default)
			)
			(layer "F.Fab")
		)
		(fp_line
			(start -0.12065 0.3048)
			(end -0.67945 0.3048)
			(stroke
				(width 0.1)
				(type default)
			)
			(layer "F.Fab")
		)
		(fp_line
			(start -0.12065 0.2794)
			(end -0.12065 0.3048)
			(stroke
				(width 0.1)
				(type default)
			)
			(layer "F.Fab")
		)
		(fp_line
			(start -0.12065 -0.2794)
			(end 0.12065 -0.2794)
			(stroke
				(width 0.1)
				(type default)
			)
			(layer "F.Fab")
		)
		(fp_line
			(start -0.12065 -0.305054)
			(end -0.12065 -0.2794)
			(stroke
				(width 0.1)
				(type default)
			)
			(layer "F.Fab")
		)
		(fp_line
			(start -0.67945 0.3048)
			(end -0.67945 -0.305054)
			(stroke
				(width 0.1)
				(type default)
			)
			(layer "F.Fab")
		)
		(fp_line
			(start -0.67945 -0.305054)
			(end -0.12065 -0.305054)
			(stroke
				(width 0.1)
				(type default)
			)
			(layer "F.Fab")
		)
		(pad "1" smd circle
			(at -0.40005 0 180)
			(size 0 0)
			(layers "F.Cu" "F.Mask" "F.Paste")
			(net "GND")
		)
		(pad "2" smd circle
			(at 0.40005 0 180)
			(size 0 0)
			(layers "F.Cu" "F.Mask" "F.Paste")
			(net "P12V_NIC5_CO_EN")
		)
	)
	(footprint ""
		(layer "F.Cu")
		(at 18.800064 -84.699856)
		(property "Reference" "H47"
			(at -4.464812 -5.279136 0)
			(unlocked yes)
			(layer "F.SilkS")
			(effects
				(font
					(size 0.7874 0.5842)
					(thickness 0.1524)
				)
				(justify left)
			)
		)
		(property "Value" ""
			(at 0 0 0)
			(layer "F.Fab")
			(effects
				(font
					(size 1.27 1.27)
				)
			)
		)
		(duplicate_pad_numbers_are_jumpers no)
		(pad "1" thru_hole circle
			(at 0 0)
			(size 10.0076 10.0076)
			(drill 5.6134)
			(layers "*.Cu" "*.Mask")
			(remove_unused_layers no)
			(net "GND")
			(clearance -1.9431)
		)
	)
	(footprint ""
		(layer "F.Cu")
		(at 381.587756 -282.018232)
		(property "Reference" "C3589"
			(at 0 0 0)
			(layer "F.SilkS")
			(hide yes)
			(effects
				(font
					(size 1.27 1.27)
				)
			)
		)
		(property "Value" ""
			(at 0 0 0)
			(layer "F.Fab")
			(effects
				(font
					(size 1.27 1.27)
				)
			)
		)
		(duplicate_pad_numbers_are_jumpers no)
		(fp_line
			(start -1.2954 -0.5842)
			(end 1.2954 -0.5842)
			(stroke
				(width 0.1524)
				(type default)
			)
			(layer "F.SilkS")
		)
		(fp_line
			(start -1.2954 0.5842)
			(end -1.2954 -0.5842)
			(stroke
				(width 0.1524)
				(type default)
			)
			(layer "F.SilkS")
		)
		(fp_line
			(start 1.2954 -0.5842)
			(end 1.2954 0.5842)
			(stroke
				(width 0.1524)
				(type default)
			)
			(layer "F.SilkS")
		)
		(fp_line
			(start 1.2954 0.5842)
			(end -1.2954 0.5842)
			(stroke
				(width 0.1524)
				(type default)
			)
			(layer "F.SilkS")
		)
		(fp_line
			(start -1.1938 -0.4064)
			(end -0.8636 -0.4064)
			(stroke
				(width 0.1)
				(type default)
			)
			(layer "F.Fab")
		)
		(fp_line
			(start -1.1938 0.4064)
			(end -1.1938 -0.4064)
			(stroke
				(width 0.1)
				(type default)
			)
			(layer "F.Fab")
		)
		(fp_line
			(start -0.8636 -0.4572)
			(end 0.8636 -0.4572)
			(stroke
				(width 0.1)
				(type default)
			)
			(layer "F.Fab")
		)
		(fp_line
			(start -0.8636 -0.4064)
			(end -0.8636 -0.4572)
			(stroke
				(width 0.1)
				(type default)
			)
			(layer "F.Fab")
		)
		(fp_line
			(start -0.8636 0.4064)
			(end -1.1938 0.4064)
			(stroke
				(width 0.1)
				(type default)
			)
			(layer "F.Fab")
		)
		(fp_line
			(start -0.8636 0.4572)
			(end -0.8636 0.4064)
			(stroke
				(width 0.1)
				(type default)
			)
			(layer "F.Fab")
		)
		(fp_line
			(start 0.8636 -0.4572)
			(end 0.8636 -0.4064)
			(stroke
				(width 0.1)
				(type default)
			)
			(layer "F.Fab")
		)
		(fp_line
			(start 0.8636 -0.4064)
			(end 1.1938 -0.4064)
			(stroke
				(width 0.1)
				(type default)
			)
			(layer "F.Fab")
		)
		(fp_line
			(start 0.8636 0.4064)
			(end 0.8636 0.4572)
			(stroke
				(width 0.1)
				(type default)
			)
			(layer "F.Fab")
		)
		(fp_line
			(start 0.8636 0.4572)
			(end -0.8636 0.4572)
			(stroke
				(width 0.1)
				(type default)
			)
			(layer "F.Fab")
		)
		(fp_line
			(start 1.1938 -0.4064)
			(end 1.1938 0.4064)
			(stroke
				(width 0.1)
				(type default)
			)
			(layer "F.Fab")
		)
		(fp_line
			(start 1.1938 0.4064)
			(end 0.8636 0.4064)
			(stroke
				(width 0.1)
				(type default)
			)
			(layer "F.Fab")
		)
		(pad "1" smd rect
			(at -0.7366 0 270)
			(size 0.7112 0.8128)
			(layers "F.Cu" "F.Mask" "F.Paste")
			(net "SYSPLL_VDDA18_PEX3")
		)
		(pad "2" smd rect
			(at 0.7366 0 270)
			(size 0.7112 0.8128)
			(layers "F.Cu" "F.Mask" "F.Paste")
			(net "GND")
		)
	)
	(footprint ""
		(layer "F.Cu")
		(at 387.62178 -350.098614 90)
		(property "Reference" "C777"
			(at 0 0 90)
			(layer "F.SilkS")
			(hide yes)
			(effects
				(font
					(size 1.27 1.27)
				)
			)
		)
		(property "Value" ""
			(at 0 0 90)
			(layer "F.Fab")
			(effects
				(font
					(size 1.27 1.27)
				)
			)
		)
		(duplicate_pad_numbers_are_jumpers no)
		(fp_line
			(start 0.299974 -0.150114)
			(end 0.299974 0.150114)
			(stroke
				(width 0.1)
				(type default)
			)
			(layer "F.Fab")
		)
		(fp_line
			(start -0.299974 -0.150114)
			(end 0.299974 -0.150114)
			(stroke
				(width 0.1)
				(type default)
			)
			(layer "F.Fab")
		)
		(fp_line
			(start 0.299974 0.150114)
			(end -0.299974 0.150114)
			(stroke
				(width 0.1)
				(type default)
			)
			(layer "F.Fab")
		)
		(fp_line
			(start -0.299974 0.150114)
			(end -0.299974 -0.150114)
			(stroke
				(width 0.1)
				(type default)
			)
			(layer "F.Fab")
		)
		(pad "1" smd rect
			(at -0.2667 0 90)
			(size 0.3048 0.381)
			(layers "F.Cu" "F.Mask" "F.Paste")
			(net "P5E_PEX3_STN6_TX_DN<104>")
		)
		(pad "2" smd rect
			(at 0.2667 0 90)
			(size 0.3048 0.381)
			(layers "F.Cu" "F.Mask" "F.Paste")
			(net "P5E_PEX3_STN6_TX_C_DN<104>")
		)
	)
	(footprint ""
		(layer "F.Cu")
		(at 425.728892 -350.098614 90)
		(property "Reference" "C811"
			(at 0 0 90)
			(layer "F.SilkS")
			(hide yes)
			(effects
				(font
					(size 1.27 1.27)
				)
			)
		)
		(property "Value" ""
			(at 0 0 90)
			(layer "F.Fab")
			(effects
				(font
					(size 1.27 1.27)
				)
			)
		)
		(duplicate_pad_numbers_are_jumpers no)
		(fp_line
			(start 0.299974 -0.150114)
			(end 0.299974 0.150114)
			(stroke
				(width 0.1)
				(type default)
			)
			(layer "F.Fab")
		)
		(fp_line
			(start -0.299974 -0.150114)
			(end 0.299974 -0.150114)
			(stroke
				(width 0.1)
				(type default)
			)
			(layer "F.Fab")
		)
		(fp_line
			(start 0.299974 0.150114)
			(end -0.299974 0.150114)
			(stroke
				(width 0.1)
				(type default)
			)
			(layer "F.Fab")
		)
		(fp_line
			(start -0.299974 0.150114)
			(end -0.299974 -0.150114)
			(stroke
				(width 0.1)
				(type default)
			)
			(layer "F.Fab")
		)
		(pad "1" smd rect
			(at -0.2667 0 90)
			(size 0.3048 0.381)
			(layers "F.Cu" "F.Mask" "F.Paste")
			(net "P5E_PEX3_STN7_TX_DN<119>")
		)
		(pad "2" smd rect
			(at 0.2667 0 90)
			(size 0.3048 0.381)
			(layers "F.Cu" "F.Mask" "F.Paste")
			(net "P5E_PEX3_STN7_TX_C_DN<119>")
		)
	)
)
